(kicad_pcb
	(version 20260206)
	(generator "pcbnew")
	(generator_version "10.0")
	(general
		(thickness 1.6)
		(legacy_teardrops no)
	)
	(paper "A4")
	(title_block
		(title "Bryce Canyon_Front Panel_16369-1_OCP.brd")
		(comment 1 "Bryce Canyon / footprints 81-87 of 154")
	)
	(layers
		(0 "F.Cu" signal "TOP")
		(4 "In1.Cu" signal "L2GND")
		(6 "In2.Cu" signal "L3VCC")
		(2 "B.Cu" signal "BOTTOM")
		(9 "F.Adhes" user "F.Adhesive")
		(11 "B.Adhes" user "B.Adhesive")
		(13 "F.Paste" user "Package Geometry/Pastemask Top")
		(15 "B.Paste" user "Package Geometry/Pastemask Bottom")
		(5 "F.SilkS" user "Ref Des/Silkscreen Top")
		(7 "B.SilkS" user "Ref Des/Silkscreen Bottom")
		(1 "F.Mask" user "Board Geometry/Soldermask Top")
		(3 "B.Mask" user "Board Geometry/Soldermask Bottom")
		(17 "Dwgs.User" user "User.Drawings")
		(19 "Cmts.User" user "User.Comments")
		(21 "Eco1.User" user "User.Eco1")
		(23 "Eco2.User" user "User.Eco2")
		(25 "Edge.Cuts" user "Board Geometry/Outline")
		(27 "Margin" user)
		(31 "F.CrtYd" user "Package Geometry/Place Bound Top")
		(29 "B.CrtYd" user "Package Geometry/Place Bound Bottom")
		(35 "F.Fab" user "Ref Des/Assembly Top")
		(33 "B.Fab" user "Ref Des/Assembly Bottom")
	)
	(footprint ""
		(layer "F.Cu")
		(at 45.9232 -27.0764 180)
		(property "Reference" "R76"
			(at 0 0 180)
			(layer "F.SilkS")
			(hide yes)
			(effects
				(font
					(size 1.27 1.27)
				)
			)
		)
		(property "Value" "0R2J-2-GP"
			(at 0.064008 -3.993896 180)
			(unlocked yes)
			(layer "F.Fab")
			(hide yes)
			(effects
				(font
					(size 1.016 1.016)
					(thickness 0.1524)
				)
			)
		)
		(property "Device Type" "R402H16"
			(at 0.064008 -5.517896 180)
			(unlocked yes)
			(layer "F.Fab")
			(hide yes)
			(effects
				(font
					(size 1.016 1.016)
					(thickness 0.1524)
				)
			)
		)
		(duplicate_pad_numbers_are_jumpers no)
		(fp_line
			(start 0.508 -0.9398)
			(end -0.508 -0.9398)
			(stroke
				(width 0.1524)
				(type default)
			)
			(layer "F.SilkS")
		)
		(fp_line
			(start -0.508 -0.9398)
			(end -0.508 0.9398)
			(stroke
				(width 0.1524)
				(type default)
			)
			(layer "F.SilkS")
		)
		(fp_rect
			(start -0.508 0.9398)
			(end 0.508 -0.9398)
			(stroke
				(width 0)
				(type default)
			)
			(fill no)
			(layer "F.CrtYd")
		)
		(fp_rect
			(start -0.508 0.9398)
			(end 0.508 -0.9398)
			(stroke
				(width 0)
				(type default)
			)
			(fill no)
			(layer "F.Fab")
		)
		(pad "1" smd custom
			(at 0 -0.4445 180)
			(size 0.1397 0.1397)
			(layers "F.Cu" "F.Mask" "F.Paste")
			(net "SYS_RESET_BTN_B_N")
			(options
				(clearance outline)
				(anchor circle)
			)
			(primitives
				(gr_poly
					(pts
						(arc
							(start -0.1778 -0.2794)
							(mid -0.249642 -0.249642)
							(end -0.2794 -0.1778)
						)
						(arc
							(start -0.2794 0.1778)
							(mid -0.249642 0.249642)
							(end -0.1778 0.2794)
						)
						(arc
							(start 0.1778 0.2794)
							(mid 0.249642 0.249642)
							(end 0.2794 0.1778)
						)
						(arc
							(start 0.2794 -0.1778)
							(mid 0.249642 -0.249642)
							(end 0.1778 -0.2794)
						)
					)
					(width 0)
					(fill yes)
				)
			)
		)
		(pad "2" smd custom
			(at 0 0.4445 180)
			(size 0.1397 0.1397)
			(layers "F.Cu" "F.Mask" "F.Paste")
			(net "SYS_RESET_BTN_B_N_R")
			(options
				(clearance outline)
				(anchor circle)
			)
			(primitives
				(gr_poly
					(pts
						(arc
							(start -0.1778 -0.2794)
							(mid -0.249642 -0.249642)
							(end -0.2794 -0.1778)
						)
						(arc
							(start -0.2794 0.1778)
							(mid -0.249642 0.249642)
							(end -0.1778 0.2794)
						)
						(arc
							(start 0.1778 0.2794)
							(mid 0.249642 0.249642)
							(end 0.2794 0.1778)
						)
						(arc
							(start 0.2794 -0.1778)
							(mid 0.249642 -0.249642)
							(end 0.1778 -0.2794)
						)
					)
					(width 0)
					(fill yes)
				)
			)
		)
	)
	(footprint ""
		(layer "F.Cu")
		(at 26.4922 -6.7818)
		(property "Reference" "C31"
			(at 0 0 0)
			(layer "F.SilkS")
			(hide yes)
			(effects
				(font
					(size 1.27 1.27)
				)
			)
		)
		(property "Value" "SCD1U16V2KX-3GP"
			(at 1.1811 -2.7051 0)
			(unlocked yes)
			(layer "F.Fab")
			(hide yes)
			(effects
				(font
					(size 1.016 1.016)
					(thickness 0.1524)
				)
			)
		)
		(property "Device Type" "C402H22"
			(at 1.1811 -4.2291 0)
			(unlocked yes)
			(layer "F.Fab")
			(hide yes)
			(effects
				(font
					(size 1.016 1.016)
					(thickness 0.1524)
				)
			)
		)
		(duplicate_pad_numbers_are_jumpers no)
		(fp_rect
			(start -0.4318 0.9525)
			(end 0.4318 -0.9525)
			(stroke
				(width 0)
				(type default)
			)
			(fill no)
			(layer "F.CrtYd")
		)
		(fp_rect
			(start -0.4318 0.9525)
			(end 0.4318 -0.9525)
			(stroke
				(width 0)
				(type default)
			)
			(fill no)
			(layer "F.Fab")
		)
		(pad "1" smd custom
			(at 0 -0.4445)
			(size 0.1524 0.1524)
			(layers "F.Cu" "F.Mask" "F.Paste")
			(net "DEBUG_HDR_A_UART_SEL")
			(options
				(clearance outline)
				(anchor circle)
			)
			(primitives
				(gr_poly
					(pts
						(arc
							(start 0.3048 -0.2032)
							(mid 0.275042 -0.275042)
							(end 0.2032 -0.3048)
						)
						(arc
							(start -0.2032 -0.3048)
							(mid -0.275042 -0.275042)
							(end -0.3048 -0.2032)
						)
						(arc
							(start -0.3048 0.2032)
							(mid -0.275042 0.275042)
							(end -0.2032 0.3048)
						)
						(arc
							(start 0.2032 0.3048)
							(mid 0.275042 0.275042)
							(end 0.3048 0.2032)
						)
					)
					(width 0)
					(fill yes)
				)
			)
		)
		(pad "2" smd custom
			(at 0 0.4445)
			(size 0.1524 0.1524)
			(layers "F.Cu" "F.Mask" "F.Paste")
			(net "GND")
			(options
				(clearance outline)
				(anchor circle)
			)
			(primitives
				(gr_poly
					(pts
						(arc
							(start 0.3048 -0.2032)
							(mid 0.275042 -0.275042)
							(end 0.2032 -0.3048)
						)
						(arc
							(start -0.2032 -0.3048)
							(mid -0.275042 -0.275042)
							(end -0.3048 -0.2032)
						)
						(arc
							(start -0.3048 0.2032)
							(mid -0.275042 0.275042)
							(end -0.2032 0.3048)
						)
						(arc
							(start 0.2032 0.3048)
							(mid 0.275042 0.275042)
							(end 0.3048 0.2032)
						)
					)
					(width 0)
					(fill yes)
				)
			)
		)
	)
	(footprint ""
		(layer "F.Cu")
		(at 50.85588 -28.8544 -90)
		(property "Reference" "R51"
			(at 0 0 270)
			(layer "F.SilkS")
			(hide yes)
			(effects
				(font
					(size 1.27 1.27)
				)
			)
		)
		(property "Value" "100KR2F-L1-GP"
			(at 0.064008 -4.679696 270)
			(unlocked yes)
			(layer "F.Fab")
			(hide yes)
			(effects
				(font
					(size 2.54 2.54)
					(thickness 0.381)
				)
			)
		)
		(property "Device Type" "R402H16"
			(at 0.064008 -6.203696 270)
			(unlocked yes)
			(layer "F.Fab")
			(hide yes)
			(effects
				(font
					(size 2.54 2.54)
					(thickness 0.381)
				)
			)
		)
		(duplicate_pad_numbers_are_jumpers no)
		(fp_line
			(start -0.508 -0.9398)
			(end -0.508 0.9398)
			(stroke
				(width 0.1524)
				(type default)
			)
			(layer "F.SilkS")
		)
		(fp_line
			(start 0.508 -0.9398)
			(end -0.508 -0.9398)
			(stroke
				(width 0.1524)
				(type default)
			)
			(layer "F.SilkS")
		)
		(fp_rect
			(start -0.508 0.9398)
			(end 0.508 -0.9398)
			(stroke
				(width 0)
				(type default)
			)
			(fill no)
			(layer "F.CrtYd")
		)
		(fp_rect
			(start -0.508 0.9398)
			(end 0.508 -0.9398)
			(stroke
				(width 0)
				(type default)
			)
			(fill no)
			(layer "F.Fab")
		)
		(pad "1" smd custom
			(at 0 -0.4445 270)
			(size 0.1397 0.1397)
			(layers "F.Cu" "F.Mask" "F.Paste")
			(net "P3V3_STBY_B")
			(options
				(clearance outline)
				(anchor circle)
			)
			(primitives
				(gr_poly
					(pts
						(arc
							(start -0.1778 -0.2794)
							(mid -0.249642 -0.249642)
							(end -0.2794 -0.1778)
						)
						(arc
							(start -0.2794 0.1778)
							(mid -0.249642 0.249642)
							(end -0.1778 0.2794)
						)
						(arc
							(start 0.1778 0.2794)
							(mid 0.249642 0.249642)
							(end 0.2794 0.1778)
						)
						(arc
							(start 0.2794 -0.1778)
							(mid 0.249642 -0.249642)
							(end 0.1778 -0.2794)
						)
					)
					(width 0)
					(fill yes)
				)
			)
		)
		(pad "2" smd custom
			(at 0 0.4445 270)
			(size 0.1397 0.1397)
			(layers "F.Cu" "F.Mask" "F.Paste")
			(net "SYS_RESET_BTN_B")
			(options
				(clearance outline)
				(anchor circle)
			)
			(primitives
				(gr_poly
					(pts
						(arc
							(start -0.1778 -0.2794)
							(mid -0.249642 -0.249642)
							(end -0.2794 -0.1778)
						)
						(arc
							(start -0.2794 0.1778)
							(mid -0.249642 0.249642)
							(end -0.1778 0.2794)
						)
						(arc
							(start 0.1778 0.2794)
							(mid 0.249642 0.249642)
							(end 0.2794 0.1778)
						)
						(arc
							(start 0.2794 -0.1778)
							(mid 0.249642 -0.249642)
							(end 0.1778 -0.2794)
						)
					)
					(width 0)
					(fill yes)
				)
			)
		)
	)
	(footprint ""
		(layer "F.Cu")
		(at 4.4958 -27.7495)
		(property "Reference" "D9"
			(at 0 0 0)
			(layer "F.SilkS")
			(hide yes)
			(effects
				(font
					(size 1.27 1.27)
				)
			)
		)
		(property "Value" "PESD5V0X1UAB-GP"
			(at 0 -4.690618 0)
			(unlocked yes)
			(layer "F.Fab")
			(hide yes)
			(effects
				(font
					(size 1.016 1.016)
					(thickness 0.1524)
				)
			)
		)
		(property "Device Type" "SOD523AKH26"
			(at 0 -6.214618 0)
			(unlocked yes)
			(layer "F.Fab")
			(hide yes)
			(effects
				(font
					(size 1.016 1.016)
					(thickness 0.1524)
				)
			)
		)
		(duplicate_pad_numbers_are_jumpers no)
		(fp_line
			(start -0.5334 -1.4478)
			(end 0.5334 -1.4478)
			(stroke
				(width 0.1524)
				(type default)
			)
			(layer "F.SilkS")
		)
		(fp_line
			(start -0.5334 1.524)
			(end -0.5334 -1.4478)
			(stroke
				(width 0.1524)
				(type default)
			)
			(layer "F.SilkS")
		)
		(fp_line
			(start 0.4064 1.651)
			(end -0.4064 1.651)
			(stroke
				(width 0.4064)
				(type default)
			)
			(layer "F.SilkS")
		)
		(fp_line
			(start 0.5334 -1.4478)
			(end 0.5334 1.524)
			(stroke
				(width 0.1524)
				(type default)
			)
			(layer "F.SilkS")
		)
		(fp_line
			(start 0.5334 1.524)
			(end -0.5334 1.524)
			(stroke
				(width 0.1524)
				(type default)
			)
			(layer "F.SilkS")
		)
		(fp_rect
			(start -0.6096 1.8542)
			(end 0.6096 -1.524)
			(stroke
				(width 0)
				(type default)
			)
			(fill no)
			(layer "F.CrtYd")
		)
		(fp_poly
			(pts
				(xy -0.6096 -1.524) (xy 0.6096 -1.524) (xy 0.6096 1.8542) (xy -0.6096 1.8542)
			)
			(stroke
				(width 0)
				(type default)
			)
			(fill no)
			(layer "F.Fab")
		)
		(pad "A" smd rect
			(at 0 -0.762)
			(size 0.5588 1.016)
			(layers "F.Cu" "F.Mask" "F.Paste")
			(net "GND")
		)
		(pad "K" smd rect
			(at 0 0.762)
			(size 0.5588 1.016)
			(layers "F.Cu" "F.Mask" "F.Paste")
			(net "SYS_RESET_BTN_A")
		)
	)
	(footprint ""
		(layer "F.Cu")
		(at 51.181 -12.827)
		(property "Reference" "R12"
			(at 0 0 0)
			(layer "F.SilkS")
			(hide yes)
			(effects
				(font
					(size 1.27 1.27)
				)
			)
		)
		(property "Value" "0R2J-2-GP"
			(at 0.064008 -4.679696 0)
			(unlocked yes)
			(layer "F.Fab")
			(hide yes)
			(effects
				(font
					(size 2.54 2.54)
					(thickness 0.381)
				)
			)
		)
		(property "Device Type" "R402H16"
			(at 0.064008 -6.203696 0)
			(unlocked yes)
			(layer "F.Fab")
			(hide yes)
			(effects
				(font
					(size 2.54 2.54)
					(thickness 0.381)
				)
			)
		)
		(duplicate_pad_numbers_are_jumpers no)
		(fp_line
			(start -0.508 -0.9398)
			(end -0.508 0.9398)
			(stroke
				(width 0.1524)
				(type default)
			)
			(layer "F.SilkS")
		)
		(fp_line
			(start 0.508 -0.9398)
			(end -0.508 -0.9398)
			(stroke
				(width 0.1524)
				(type default)
			)
			(layer "F.SilkS")
		)
		(fp_rect
			(start -0.508 0.9398)
			(end 0.508 -0.9398)
			(stroke
				(width 0)
				(type default)
			)
			(fill no)
			(layer "F.CrtYd")
		)
		(fp_rect
			(start -0.508 0.9398)
			(end 0.508 -0.9398)
			(stroke
				(width 0)
				(type default)
			)
			(fill no)
			(layer "F.Fab")
		)
		(pad "1" smd custom
			(at 0 -0.4445)
			(size 0.1397 0.1397)
			(layers "F.Cu" "F.Mask" "F.Paste")
			(net "I2C_DEBUG_B_SDA_R")
			(options
				(clearance outline)
				(anchor circle)
			)
			(primitives
				(gr_poly
					(pts
						(arc
							(start -0.1778 -0.2794)
							(mid -0.249642 -0.249642)
							(end -0.2794 -0.1778)
						)
						(arc
							(start -0.2794 0.1778)
							(mid -0.249642 0.249642)
							(end -0.1778 0.2794)
						)
						(arc
							(start 0.1778 0.2794)
							(mid 0.249642 0.249642)
							(end 0.2794 0.1778)
						)
						(arc
							(start 0.2794 -0.1778)
							(mid 0.249642 -0.249642)
							(end 0.1778 -0.2794)
						)
					)
					(width 0)
					(fill yes)
				)
			)
		)
		(pad "2" smd custom
			(at 0 0.4445)
			(size 0.1397 0.1397)
			(layers "F.Cu" "F.Mask" "F.Paste")
			(net "I2C_DEBUG_B_SDA_L")
			(options
				(clearance outline)
				(anchor circle)
			)
			(primitives
				(gr_poly
					(pts
						(arc
							(start -0.1778 -0.2794)
							(mid -0.249642 -0.249642)
							(end -0.2794 -0.1778)
						)
						(arc
							(start -0.2794 0.1778)
							(mid -0.249642 0.249642)
							(end -0.1778 0.2794)
						)
						(arc
							(start 0.1778 0.2794)
							(mid 0.249642 0.249642)
							(end 0.2794 0.1778)
						)
						(arc
							(start 0.2794 -0.1778)
							(mid 0.249642 -0.249642)
							(end 0.1778 -0.2794)
						)
					)
					(width 0)
					(fill yes)
				)
			)
		)
	)
	(footprint ""
		(layer "F.Cu")
		(at 47.359316 -72.650096 180)
		(property "Reference" "C9"
			(at 0 0 180)
			(layer "F.SilkS")
			(hide yes)
			(effects
				(font
					(size 1.27 1.27)
				)
			)
		)
		(property "Value" "SC1U16V3KX-5GP"
			(at 0 -3.5052 180)
			(unlocked yes)
			(layer "F.Fab")
			(hide yes)
			(effects
				(font
					(size 2.54 2.54)
					(thickness 0.381)
				)
			)
		)
		(property "Device Type" "C603H36"
			(at 0 -5.0292 180)
			(unlocked yes)
			(layer "F.Fab")
			(hide yes)
			(effects
				(font
					(size 2.54 2.54)
					(thickness 0.381)
				)
			)
		)
		(duplicate_pad_numbers_are_jumpers no)
		(fp_line
			(start 0.508 0)
			(end -0.508 0)
			(stroke
				(width 0.2032)
				(type default)
			)
			(layer "F.SilkS")
		)
		(fp_rect
			(start -0.5842 1.3335)
			(end 0.5842 -1.3335)
			(stroke
				(width 0)
				(type default)
			)
			(fill no)
			(layer "F.CrtYd")
		)
		(fp_rect
			(start -0.5842 1.3335)
			(end 0.5842 -1.3335)
			(stroke
				(width 0)
				(type default)
			)
			(fill no)
			(layer "F.Fab")
		)
		(pad "1" smd custom
			(at 0 -0.762 180)
			(size 0.2159 0.2159)
			(layers "F.Cu" "F.Mask" "F.Paste")
			(net "P5V_USB_B")
			(options
				(clearance outline)
				(anchor circle)
			)
			(primitives
				(gr_poly
					(pts
						(arc
							(start -0.3302 -0.4318)
							(mid -0.402042 -0.402042)
							(end -0.4318 -0.3302)
						)
						(arc
							(start -0.4318 0.3302)
							(mid -0.402042 0.402042)
							(end -0.3302 0.4318)
						)
						(arc
							(start 0.3302 0.4318)
							(mid 0.402042 0.402042)
							(end 0.4318 0.3302)
						)
						(arc
							(start 0.4318 -0.3302)
							(mid 0.402042 -0.402042)
							(end 0.3302 -0.4318)
						)
					)
					(width 0)
					(fill yes)
				)
			)
		)
		(pad "2" smd custom
			(at 0 0.762 180)
			(size 0.2159 0.2159)
			(layers "F.Cu" "F.Mask" "F.Paste")
			(net "GND")
			(options
				(clearance outline)
				(anchor circle)
			)
			(primitives
				(gr_poly
					(pts
						(arc
							(start -0.3302 -0.4318)
							(mid -0.402042 -0.402042)
							(end -0.4318 -0.3302)
						)
						(arc
							(start -0.4318 0.3302)
							(mid -0.402042 0.402042)
							(end -0.3302 0.4318)
						)
						(arc
							(start 0.3302 0.4318)
							(mid 0.402042 0.402042)
							(end 0.4318 0.3302)
						)
						(arc
							(start 0.4318 -0.3302)
							(mid 0.402042 -0.402042)
							(end 0.3302 -0.4318)
						)
					)
					(width 0)
					(fill yes)
				)
			)
		)
	)
	(footprint ""
		(layer "F.Cu")
		(at 7.9756 -17.9832 -90)
		(property "Reference" "R55"
			(at 0 0 270)
			(layer "F.SilkS")
			(hide yes)
			(effects
				(font
					(size 1.27 1.27)
				)
			)
		)
		(property "Value" "20KR2F-L-GP"
			(at 0.064008 -3.993896 270)
			(unlocked yes)
			(layer "F.Fab")
			(hide yes)
			(effects
				(font
					(size 1.016 1.016)
					(thickness 0.1524)
				)
			)
		)
		(property "Device Type" "R402H16"
			(at 0.064008 -5.517896 270)
			(unlocked yes)
			(layer "F.Fab")
			(hide yes)
			(effects
				(font
					(size 1.016 1.016)
					(thickness 0.1524)
				)
			)
		)
		(duplicate_pad_numbers_are_jumpers no)
		(fp_line
			(start -0.508 -0.9398)
			(end -0.508 0.9398)
			(stroke
				(width 0.1524)
				(type default)
			)
			(layer "F.SilkS")
		)
		(fp_line
			(start 0.508 -0.9398)
			(end -0.508 -0.9398)
			(stroke
				(width 0.1524)
				(type default)
			)
			(layer "F.SilkS")
		)
		(fp_rect
			(start -0.508 0.9398)
			(end 0.508 -0.9398)
			(stroke
				(width 0)
				(type default)
			)
			(fill no)
			(layer "F.CrtYd")
		)
		(fp_rect
			(start -0.508 0.9398)
			(end 0.508 -0.9398)
			(stroke
				(width 0)
				(type default)
			)
			(fill no)
			(layer "F.Fab")
		)
		(pad "1" smd custom
			(at 0 -0.4445 270)
			(size 0.1397 0.1397)
			(layers "F.Cu" "F.Mask" "F.Paste")
			(net "P3V3_STBY_A")
			(options
				(clearance outline)
				(anchor circle)
			)
			(primitives
				(gr_poly
					(pts
						(arc
							(start -0.1778 -0.2794)
							(mid -0.249642 -0.249642)
							(end -0.2794 -0.1778)
						)
						(arc
							(start -0.2794 0.1778)
							(mid -0.249642 0.249642)
							(end -0.1778 0.2794)
						)
						(arc
							(start 0.1778 0.2794)
							(mid 0.249642 0.249642)
							(end 0.2794 0.1778)
						)
						(arc
							(start 0.2794 -0.1778)
							(mid 0.249642 -0.249642)
							(end 0.1778 -0.2794)
						)
					)
					(width 0)
					(fill yes)
				)
			)
		)
		(pad "2" smd custom
			(at 0 0.4445 270)
			(size 0.1397 0.1397)
			(layers "F.Cu" "F.Mask" "F.Paste")
			(net "I2C_DEBUG_A_SDA_L")
			(options
				(clearance outline)
				(anchor circle)
			)
			(primitives
				(gr_poly
					(pts
						(arc
							(start -0.1778 -0.2794)
							(mid -0.249642 -0.249642)
							(end -0.2794 -0.1778)
						)
						(arc
							(start -0.2794 0.1778)
							(mid -0.249642 0.249642)
							(end -0.1778 0.2794)
						)
						(arc
							(start 0.1778 0.2794)
							(mid 0.249642 0.249642)
							(end 0.2794 0.1778)
						)
						(arc
							(start 0.2794 -0.1778)
							(mid 0.249642 -0.249642)
							(end 0.1778 -0.2794)
						)
					)
					(width 0)
					(fill yes)
				)
			)
		)
	)
)
